(kicad_pcb
	(version 20260206)
	(generator "pcbnew")
	(generator_version "10.0")
	(general
		(thickness 1.6)
		(legacy_teardrops no)
	)
	(paper "A4")
	(title_block
		(title "peb — Lightning_PEB_BRD.brd")
		(comment 1 "Lightning (Wiwynn / Facebook NVMe JBOF) / footprints 1065-1071 of 2563")
	)
	(layers
		(0 "F.Cu" signal "TOP")
		(4 "In1.Cu" signal "L2GND")
		(6 "In2.Cu" signal "L3")
		(8 "In3.Cu" signal "L4VCC")
		(10 "In4.Cu" signal "L5VCC")
		(12 "In5.Cu" signal "L6")
		(14 "In6.Cu" signal "L7GND")
		(2 "B.Cu" signal "BOTTOM")
		(9 "F.Adhes" user "F.Adhesive")
		(11 "B.Adhes" user "B.Adhesive")
		(13 "F.Paste" user "Package Geometry/Pastemask Top")
		(15 "B.Paste" user "Package Geometry/Pastemask Bottom")
		(5 "F.SilkS" user "Ref Des/Silkscreen Top")
		(7 "B.SilkS" user "Ref Des/Silkscreen Bottom")
		(1 "F.Mask" user "Board Geometry/Soldermask Top")
		(3 "B.Mask" user "Board Geometry/Soldermask Bottom")
		(17 "Dwgs.User" user "User.Drawings")
		(19 "Cmts.User" user "User.Comments")
		(21 "Eco1.User" user "User.Eco1")
		(23 "Eco2.User" user "User.Eco2")
		(25 "Edge.Cuts" user "Board Geometry/Outline")
		(27 "Margin" user)
		(31 "F.CrtYd" user "Package Geometry/Place Bound Top")
		(29 "B.CrtYd" user "Package Geometry/Place Bound Bottom")
		(35 "F.Fab" user "Ref Des/Assembly Top")
		(33 "B.Fab" user "Ref Des/Assembly Bottom")
	)
	(footprint ""
		(layer "F.Cu")
		(at 338.868512 -172.432218)
		(property "Reference" "R7954"
			(at 0 0 0)
			(layer "F.SilkS")
			(hide yes)
			(effects
				(font
					(size 1.27 1.27)
				)
			)
		)
		(property "Value" "0R2J-2-GP"
			(at 0.064008 -3.993896 0)
			(unlocked yes)
			(layer "F.Fab")
			(hide yes)
			(effects
				(font
					(size 1.016 1.016)
					(thickness 0.1524)
				)
			)
		)
		(property "Device Type" "R402H16"
			(at 0.064008 -5.517896 0)
			(unlocked yes)
			(layer "F.Fab")
			(hide yes)
			(effects
				(font
					(size 1.016 1.016)
					(thickness 0.1524)
				)
			)
		)
		(duplicate_pad_numbers_are_jumpers no)
		(fp_line
			(start -0.508 -0.9398)
			(end -0.508 0.9398)
			(stroke
				(width 0.1524)
				(type default)
			)
			(layer "F.SilkS")
		)
		(fp_line
			(start 0.508 -0.9398)
			(end -0.508 -0.9398)
			(stroke
				(width 0.1524)
				(type default)
			)
			(layer "F.SilkS")
		)
		(fp_rect
			(start -0.508 0.9398)
			(end 0.508 -0.9398)
			(stroke
				(width 0)
				(type default)
			)
			(fill no)
			(layer "F.CrtYd")
		)
		(fp_rect
			(start -0.508 0.9398)
			(end 0.508 -0.9398)
			(stroke
				(width 0)
				(type default)
			)
			(fill no)
			(layer "F.Fab")
		)
		(pad "1" smd custom
			(at 0 -0.4445)
			(size 0.1397 0.1397)
			(layers "F.Cu" "F.Mask" "F.Paste")
			(net "SSD_PWREN9")
			(options
				(clearance outline)
				(anchor circle)
			)
			(primitives
				(gr_poly
					(pts
						(arc
							(start -0.1778 -0.2794)
							(mid -0.249642 -0.249642)
							(end -0.2794 -0.1778)
						)
						(arc
							(start -0.2794 0.1778)
							(mid -0.249642 0.249642)
							(end -0.1778 0.2794)
						)
						(arc
							(start 0.1778 0.2794)
							(mid 0.249642 0.249642)
							(end 0.2794 0.1778)
						)
						(arc
							(start 0.2794 -0.1778)
							(mid 0.249642 -0.249642)
							(end 0.1778 -0.2794)
						)
					)
					(width 0)
					(fill yes)
				)
			)
		)
		(pad "2" smd custom
			(at 0 0.4445)
			(size 0.1397 0.1397)
			(layers "F.Cu" "F.Mask" "F.Paste")
			(net "SSD_PWREN9_R")
			(options
				(clearance outline)
				(anchor circle)
			)
			(primitives
				(gr_poly
					(pts
						(arc
							(start -0.1778 -0.2794)
							(mid -0.249642 -0.249642)
							(end -0.2794 -0.1778)
						)
						(arc
							(start -0.2794 0.1778)
							(mid -0.249642 0.249642)
							(end -0.1778 0.2794)
						)
						(arc
							(start 0.1778 0.2794)
							(mid 0.249642 0.249642)
							(end 0.2794 0.1778)
						)
						(arc
							(start 0.2794 -0.1778)
							(mid 0.249642 -0.249642)
							(end 0.1778 -0.2794)
						)
					)
					(width 0)
					(fill yes)
				)
			)
		)
	)
	(footprint ""
		(layer "F.Cu")
		(at 226.822 -23.241 180)
		(property "Reference" "R3719"
			(at 0 0 180)
			(layer "F.SilkS")
			(hide yes)
			(effects
				(font
					(size 1.27 1.27)
				)
			)
		)
		(property "Value" "4K7R2F-GP"
			(at 0.064008 -3.993896 180)
			(unlocked yes)
			(layer "F.Fab")
			(hide yes)
			(effects
				(font
					(size 1.016 1.016)
					(thickness 0.1524)
				)
			)
		)
		(property "Device Type" "R402H16"
			(at 0.064008 -5.517896 180)
			(unlocked yes)
			(layer "F.Fab")
			(hide yes)
			(effects
				(font
					(size 1.016 1.016)
					(thickness 0.1524)
				)
			)
		)
		(duplicate_pad_numbers_are_jumpers no)
		(fp_line
			(start 0.508 -0.9398)
			(end -0.508 -0.9398)
			(stroke
				(width 0.1524)
				(type default)
			)
			(layer "F.SilkS")
		)
		(fp_line
			(start -0.508 -0.9398)
			(end -0.508 0.9398)
			(stroke
				(width 0.1524)
				(type default)
			)
			(layer "F.SilkS")
		)
		(fp_rect
			(start -0.508 0.9398)
			(end 0.508 -0.9398)
			(stroke
				(width 0)
				(type default)
			)
			(fill no)
			(layer "F.CrtYd")
		)
		(fp_rect
			(start -0.508 0.9398)
			(end 0.508 -0.9398)
			(stroke
				(width 0)
				(type default)
			)
			(fill no)
			(layer "F.Fab")
		)
		(pad "1" smd custom
			(at 0 -0.4445 180)
			(size 0.1397 0.1397)
			(layers "F.Cu" "F.Mask" "F.Paste")
			(net "HOST4_RST_N_LS")
			(options
				(clearance outline)
				(anchor circle)
			)
			(primitives
				(gr_poly
					(pts
						(arc
							(start -0.1778 -0.2794)
							(mid -0.249642 -0.249642)
							(end -0.2794 -0.1778)
						)
						(arc
							(start -0.2794 0.1778)
							(mid -0.249642 0.249642)
							(end -0.1778 0.2794)
						)
						(arc
							(start 0.1778 0.2794)
							(mid 0.249642 0.249642)
							(end 0.2794 0.1778)
						)
						(arc
							(start 0.2794 -0.1778)
							(mid 0.249642 -0.249642)
							(end 0.1778 -0.2794)
						)
					)
					(width 0)
					(fill yes)
				)
			)
		)
		(pad "2" smd custom
			(at 0 0.4445 180)
			(size 0.1397 0.1397)
			(layers "F.Cu" "F.Mask" "F.Paste")
			(net "GND")
			(options
				(clearance outline)
				(anchor circle)
			)
			(primitives
				(gr_poly
					(pts
						(arc
							(start -0.1778 -0.2794)
							(mid -0.249642 -0.249642)
							(end -0.2794 -0.1778)
						)
						(arc
							(start -0.2794 0.1778)
							(mid -0.249642 0.249642)
							(end -0.1778 0.2794)
						)
						(arc
							(start 0.1778 0.2794)
							(mid 0.249642 0.249642)
							(end 0.2794 0.1778)
						)
						(arc
							(start 0.2794 -0.1778)
							(mid 0.249642 -0.249642)
							(end 0.1778 -0.2794)
						)
					)
					(width 0)
					(fill yes)
				)
			)
		)
	)
	(footprint ""
		(layer "F.Cu")
		(at 25.019 -152.4)
		(property "Reference" "C3217"
			(at 0 0 0)
			(layer "F.SilkS")
			(hide yes)
			(effects
				(font
					(size 1.27 1.27)
				)
			)
		)
		(property "Value" "SCD1U25V2KX-2-GP"
			(at 1.1811 -2.7051 0)
			(unlocked yes)
			(layer "F.Fab")
			(hide yes)
			(effects
				(font
					(size 1.016 1.016)
					(thickness 0.1524)
				)
			)
		)
		(property "Device Type" "C402H22"
			(at 1.1811 -4.2291 0)
			(unlocked yes)
			(layer "F.Fab")
			(hide yes)
			(effects
				(font
					(size 1.016 1.016)
					(thickness 0.1524)
				)
			)
		)
		(duplicate_pad_numbers_are_jumpers no)
		(fp_rect
			(start -0.4318 0.9525)
			(end 0.4318 -0.9525)
			(stroke
				(width 0)
				(type default)
			)
			(fill no)
			(layer "F.CrtYd")
		)
		(fp_rect
			(start -0.4318 0.9525)
			(end 0.4318 -0.9525)
			(stroke
				(width 0)
				(type default)
			)
			(fill no)
			(layer "F.Fab")
		)
		(pad "1" smd custom
			(at 0 -0.4445)
			(size 0.1524 0.1524)
			(layers "F.Cu" "F.Mask" "F.Paste")
			(net "P3V3_STBY")
			(options
				(clearance outline)
				(anchor circle)
			)
			(primitives
				(gr_poly
					(pts
						(arc
							(start 0.3048 -0.2032)
							(mid 0.275042 -0.275042)
							(end 0.2032 -0.3048)
						)
						(arc
							(start -0.2032 -0.3048)
							(mid -0.275042 -0.275042)
							(end -0.3048 -0.2032)
						)
						(arc
							(start -0.3048 0.2032)
							(mid -0.275042 0.275042)
							(end -0.2032 0.3048)
						)
						(arc
							(start 0.2032 0.3048)
							(mid 0.275042 0.275042)
							(end 0.3048 0.2032)
						)
					)
					(width 0)
					(fill yes)
				)
			)
		)
		(pad "2" smd custom
			(at 0 0.4445)
			(size 0.1524 0.1524)
			(layers "F.Cu" "F.Mask" "F.Paste")
			(net "GND")
			(options
				(clearance outline)
				(anchor circle)
			)
			(primitives
				(gr_poly
					(pts
						(arc
							(start 0.3048 -0.2032)
							(mid 0.275042 -0.275042)
							(end 0.2032 -0.3048)
						)
						(arc
							(start -0.2032 -0.3048)
							(mid -0.275042 -0.275042)
							(end -0.3048 -0.2032)
						)
						(arc
							(start -0.3048 0.2032)
							(mid -0.275042 0.275042)
							(end -0.2032 0.3048)
						)
						(arc
							(start 0.2032 0.3048)
							(mid 0.275042 0.275042)
							(end 0.3048 0.2032)
						)
					)
					(width 0)
					(fill yes)
				)
			)
		)
	)
	(footprint ""
		(layer "F.Cu")
		(at 40.64 -197.231)
		(property "Reference" "R879"
			(at 0 0 0)
			(layer "F.SilkS")
			(hide yes)
			(effects
				(font
					(size 1.27 1.27)
				)
			)
		)
		(property "Value" "0R2J-2-GP"
			(at 0.064008 -3.993896 0)
			(unlocked yes)
			(layer "F.Fab")
			(hide yes)
			(effects
				(font
					(size 1.016 1.016)
					(thickness 0.1524)
				)
			)
		)
		(property "Device Type" "R402H16"
			(at 0.064008 -5.517896 0)
			(unlocked yes)
			(layer "F.Fab")
			(hide yes)
			(effects
				(font
					(size 1.016 1.016)
					(thickness 0.1524)
				)
			)
		)
		(duplicate_pad_numbers_are_jumpers no)
		(fp_line
			(start -0.508 -0.9398)
			(end -0.508 0.9398)
			(stroke
				(width 0.1524)
				(type default)
			)
			(layer "F.SilkS")
		)
		(fp_line
			(start 0.508 -0.9398)
			(end -0.508 -0.9398)
			(stroke
				(width 0.1524)
				(type default)
			)
			(layer "F.SilkS")
		)
		(fp_rect
			(start -0.508 0.9398)
			(end 0.508 -0.9398)
			(stroke
				(width 0)
				(type default)
			)
			(fill no)
			(layer "F.CrtYd")
		)
		(fp_rect
			(start -0.508 0.9398)
			(end 0.508 -0.9398)
			(stroke
				(width 0)
				(type default)
			)
			(fill no)
			(layer "F.Fab")
		)
		(pad "1" smd custom
			(at 0 -0.4445)
			(size 0.1397 0.1397)
			(layers "F.Cu" "F.Mask" "F.Paste")
			(net "BMC_I2C6_C_FCB_SDA_R")
			(options
				(clearance outline)
				(anchor circle)
			)
			(primitives
				(gr_poly
					(pts
						(arc
							(start -0.1778 -0.2794)
							(mid -0.249642 -0.249642)
							(end -0.2794 -0.1778)
						)
						(arc
							(start -0.2794 0.1778)
							(mid -0.249642 0.249642)
							(end -0.1778 0.2794)
						)
						(arc
							(start 0.1778 0.2794)
							(mid 0.249642 0.249642)
							(end 0.2794 0.1778)
						)
						(arc
							(start 0.2794 -0.1778)
							(mid 0.249642 -0.249642)
							(end 0.1778 -0.2794)
						)
					)
					(width 0)
					(fill yes)
				)
			)
		)
		(pad "2" smd custom
			(at 0 0.4445)
			(size 0.1397 0.1397)
			(layers "F.Cu" "F.Mask" "F.Paste")
			(net "BMC_I2C6_C_FCB_SDA")
			(options
				(clearance outline)
				(anchor circle)
			)
			(primitives
				(gr_poly
					(pts
						(arc
							(start -0.1778 -0.2794)
							(mid -0.249642 -0.249642)
							(end -0.2794 -0.1778)
						)
						(arc
							(start -0.2794 0.1778)
							(mid -0.249642 0.249642)
							(end -0.1778 0.2794)
						)
						(arc
							(start 0.1778 0.2794)
							(mid 0.249642 0.249642)
							(end 0.2794 0.1778)
						)
						(arc
							(start 0.2794 -0.1778)
							(mid 0.249642 -0.249642)
							(end 0.1778 -0.2794)
						)
					)
					(width 0)
					(fill yes)
				)
			)
		)
	)
	(footprint ""
		(layer "F.Cu")
		(at 134.1882 -42.11701 -90)
		(property "Reference" "R771"
			(at 0 0 270)
			(layer "F.SilkS")
			(hide yes)
			(effects
				(font
					(size 1.27 1.27)
				)
			)
		)
		(property "Value" "4K7R2F-GP"
			(at 0.064008 -3.993896 270)
			(unlocked yes)
			(layer "F.Fab")
			(hide yes)
			(effects
				(font
					(size 1.016 1.016)
					(thickness 0.1524)
				)
			)
		)
		(property "Device Type" "R402H16"
			(at 0.064008 -5.517896 270)
			(unlocked yes)
			(layer "F.Fab")
			(hide yes)
			(effects
				(font
					(size 1.016 1.016)
					(thickness 0.1524)
				)
			)
		)
		(duplicate_pad_numbers_are_jumpers no)
		(fp_line
			(start -0.508 -0.9398)
			(end -0.508 0.9398)
			(stroke
				(width 0.1524)
				(type default)
			)
			(layer "F.SilkS")
		)
		(fp_line
			(start 0.508 -0.9398)
			(end -0.508 -0.9398)
			(stroke
				(width 0.1524)
				(type default)
			)
			(layer "F.SilkS")
		)
		(fp_rect
			(start -0.508 0.9398)
			(end 0.508 -0.9398)
			(stroke
				(width 0)
				(type default)
			)
			(fill no)
			(layer "F.CrtYd")
		)
		(fp_rect
			(start -0.508 0.9398)
			(end 0.508 -0.9398)
			(stroke
				(width 0)
				(type default)
			)
			(fill no)
			(layer "F.Fab")
		)
		(pad "1" smd custom
			(at 0 -0.4445 270)
			(size 0.1397 0.1397)
			(layers "F.Cu" "F.Mask" "F.Paste")
			(net "DUT_VDDO")
			(options
				(clearance outline)
				(anchor circle)
			)
			(primitives
				(gr_poly
					(pts
						(arc
							(start -0.1778 -0.2794)
							(mid -0.249642 -0.249642)
							(end -0.2794 -0.1778)
						)
						(arc
							(start -0.2794 0.1778)
							(mid -0.249642 0.249642)
							(end -0.1778 0.2794)
						)
						(arc
							(start 0.1778 0.2794)
							(mid 0.249642 0.249642)
							(end 0.2794 0.1778)
						)
						(arc
							(start 0.2794 -0.1778)
							(mid 0.249642 -0.249642)
							(end 0.1778 -0.2794)
						)
					)
					(width 0)
					(fill yes)
				)
			)
		)
		(pad "2" smd custom
			(at 0 0.4445 270)
			(size 0.1397 0.1397)
			(layers "F.Cu" "F.Mask" "F.Paste")
			(net "EJTAG_TDI")
			(options
				(clearance outline)
				(anchor circle)
			)
			(primitives
				(gr_poly
					(pts
						(arc
							(start -0.1778 -0.2794)
							(mid -0.249642 -0.249642)
							(end -0.2794 -0.1778)
						)
						(arc
							(start -0.2794 0.1778)
							(mid -0.249642 0.249642)
							(end -0.1778 0.2794)
						)
						(arc
							(start 0.1778 0.2794)
							(mid 0.249642 0.249642)
							(end 0.2794 0.1778)
						)
						(arc
							(start 0.2794 -0.1778)
							(mid 0.249642 -0.249642)
							(end 0.1778 -0.2794)
						)
					)
					(width 0)
					(fill yes)
				)
			)
		)
	)
	(footprint ""
		(layer "F.Cu")
		(at 202.3364 -18.8468 -90)
		(property "Reference" "R702"
			(at 0 0 270)
			(layer "F.SilkS")
			(hide yes)
			(effects
				(font
					(size 1.27 1.27)
				)
			)
		)
		(property "Value" "4K7R2F-GP"
			(at 0.064008 -3.993896 270)
			(unlocked yes)
			(layer "F.Fab")
			(hide yes)
			(effects
				(font
					(size 1.016 1.016)
					(thickness 0.1524)
				)
			)
		)
		(property "Device Type" "R402H16"
			(at 0.064008 -5.517896 270)
			(unlocked yes)
			(layer "F.Fab")
			(hide yes)
			(effects
				(font
					(size 1.016 1.016)
					(thickness 0.1524)
				)
			)
		)
		(duplicate_pad_numbers_are_jumpers no)
		(fp_line
			(start -0.508 -0.9398)
			(end -0.508 0.9398)
			(stroke
				(width 0.1524)
				(type default)
			)
			(layer "F.SilkS")
		)
		(fp_line
			(start 0.508 -0.9398)
			(end -0.508 -0.9398)
			(stroke
				(width 0.1524)
				(type default)
			)
			(layer "F.SilkS")
		)
		(fp_rect
			(start -0.508 0.9398)
			(end 0.508 -0.9398)
			(stroke
				(width 0)
				(type default)
			)
			(fill no)
			(layer "F.CrtYd")
		)
		(fp_rect
			(start -0.508 0.9398)
			(end 0.508 -0.9398)
			(stroke
				(width 0)
				(type default)
			)
			(fill no)
			(layer "F.Fab")
		)
		(pad "1" smd custom
			(at 0 -0.4445 270)
			(size 0.1397 0.1397)
			(layers "F.Cu" "F.Mask" "F.Paste")
			(net "MINISAS_CN16_C_I2C_INT#")
			(options
				(clearance outline)
				(anchor circle)
			)
			(primitives
				(gr_poly
					(pts
						(arc
							(start -0.1778 -0.2794)
							(mid -0.249642 -0.249642)
							(end -0.2794 -0.1778)
						)
						(arc
							(start -0.2794 0.1778)
							(mid -0.249642 0.249642)
							(end -0.1778 0.2794)
						)
						(arc
							(start 0.1778 0.2794)
							(mid 0.249642 0.249642)
							(end 0.2794 0.1778)
						)
						(arc
							(start 0.2794 -0.1778)
							(mid 0.249642 -0.249642)
							(end 0.1778 -0.2794)
						)
					)
					(width 0)
					(fill yes)
				)
			)
		)
		(pad "2" smd custom
			(at 0 0.4445 270)
			(size 0.1397 0.1397)
			(layers "F.Cu" "F.Mask" "F.Paste")
			(net "P3V3_STBY")
			(options
				(clearance outline)
				(anchor circle)
			)
			(primitives
				(gr_poly
					(pts
						(arc
							(start -0.1778 -0.2794)
							(mid -0.249642 -0.249642)
							(end -0.2794 -0.1778)
						)
						(arc
							(start -0.2794 0.1778)
							(mid -0.249642 0.249642)
							(end -0.1778 0.2794)
						)
						(arc
							(start 0.1778 0.2794)
							(mid 0.249642 0.249642)
							(end 0.2794 0.1778)
						)
						(arc
							(start 0.2794 -0.1778)
							(mid 0.249642 -0.249642)
							(end 0.1778 -0.2794)
						)
					)
					(width 0)
					(fill yes)
				)
			)
		)
	)
	(footprint ""
		(layer "F.Cu")
		(at 190.600076 -17.500092 -90)
		(property "Reference" "LED20"
			(at 0 0 270)
			(layer "F.SilkS")
			(hide yes)
			(effects
				(font
					(size 1.27 1.27)
				)
			)
		)
		(property "Value" "LED-YG-51-GP"
			(at -2.6924 -1.4224 270)
			(unlocked yes)
			(layer "F.Fab")
			(hide yes)
			(effects
				(font
					(size 1.016 1.016)
					(thickness 0.1524)
				)
			)
		)
		(property "Device Type" "LED1608AKH40"
			(at -2.6924 -2.9464 270)
			(unlocked yes)
			(layer "F.Fab")
			(hide yes)
			(effects
				(font
					(size 1.016 1.016)
					(thickness 0.1524)
				)
			)
		)
		(duplicate_pad_numbers_are_jumpers no)
		(fp_line
			(start -0.7493 1.651)
			(end -0.7493 1.1811)
			(stroke
				(width 0.3302)
				(type default)
			)
			(layer "F.SilkS")
		)
		(fp_line
			(start 0.7493 1.651)
			(end 0.7493 1.1811)
			(stroke
				(width 0.3302)
				(type default)
			)
			(layer "F.SilkS")
		)
		(fp_line
			(start -0.5969 1.5494)
			(end 0.5842 1.5494)
			(stroke
				(width 0.508)
				(type default)
			)
			(layer "F.SilkS")
		)
		(fp_line
			(start -0.6604 1.3716)
			(end -0.6604 -1.3716)
			(stroke
				(width 0.1524)
				(type default)
			)
			(layer "F.SilkS")
		)
		(fp_line
			(start 0.6604 1.3716)
			(end -0.6604 1.3716)
			(stroke
				(width 0.1524)
				(type default)
			)
			(layer "F.SilkS")
		)
		(fp_line
			(start -0.6604 -1.3716)
			(end 0.6604 -1.3716)
			(stroke
				(width 0.1524)
				(type default)
			)
			(layer "F.SilkS")
		)
		(fp_line
			(start 0.6604 -1.3716)
			(end 0.6604 1.3716)
			(stroke
				(width 0.1524)
				(type default)
			)
			(layer "F.SilkS")
		)
		(fp_rect
			(start -0.6223 1.3335)
			(end 0.6223 -1.3335)
			(stroke
				(width 0)
				(type default)
			)
			(fill no)
			(layer "F.CrtYd")
		)
		(fp_rect
			(start -0.6223 1.3335)
			(end 0.6223 -1.3335)
			(stroke
				(width 0)
				(type default)
			)
			(fill no)
			(layer "F.Fab")
		)
		(pad "A" smd custom
			(at 0 -0.762 270)
			(size 0.2159 0.2159)
			(layers "F.Cu" "F.Mask" "F.Paste")
			(net "LED_R_11")
			(options
				(clearance outline)
				(anchor circle)
			)
			(primitives
				(gr_poly
					(pts
						(arc
							(start -0.3302 -0.4318)
							(mid -0.402042 -0.402042)
							(end -0.4318 -0.3302)
						)
						(arc
							(start -0.4318 0.3302)
							(mid -0.402042 0.402042)
							(end -0.3302 0.4318)
						)
						(arc
							(start 0.3302 0.4318)
							(mid 0.402042 0.402042)
							(end 0.4318 0.3302)
						)
						(arc
							(start 0.4318 -0.3302)
							(mid 0.402042 -0.402042)
							(end 0.3302 -0.4318)
						)
					)
					(width 0)
					(fill yes)
				)
			)
		)
		(pad "K" smd custom
			(at 0 0.762 270)
			(size 0.2159 0.2159)
			(layers "F.Cu" "F.Mask" "F.Paste")
			(net "LED_Q_11")
			(options
				(clearance outline)
				(anchor circle)
			)
			(primitives
				(gr_poly
					(pts
						(arc
							(start -0.3302 -0.4318)
							(mid -0.402042 -0.402042)
							(end -0.4318 -0.3302)
						)
						(arc
							(start -0.4318 0.3302)
							(mid -0.402042 0.402042)
							(end -0.3302 0.4318)
						)
						(arc
							(start 0.3302 0.4318)
							(mid 0.402042 0.402042)
							(end 0.4318 0.3302)
						)
						(arc
							(start 0.4318 -0.3302)
							(mid 0.402042 -0.402042)
							(end 0.3302 -0.4318)
						)
					)
					(width 0)
					(fill yes)
				)
			)
		)
	)
)
